
INPUT-UNITS     INCHES

WHEEL     1

RECTANGLE         12        20   0.00000  D10
RECTANGLE         20        12   0.00000  D11
RECTANGLE         16        24   0.00000  D12
RECTANGLE         24        16   0.00000  D13
RECTANGLE         25        48   0.00000  D14
RECTANGLE         48        25   0.00000  D15
RECTANGLE         29        52   0.00000  D16
RECTANGLE         52        29   0.00000  D17
CIRCLE           241            D18
FLASH     TR237X251X40-45      0.00000  D19
CIRCLE           394            D20
CIRCLE           398            D21
RECTANGLE         24        44   0.00000  D22
RECTANGLE         44        24   0.00000  D23
RECTANGLE         28        48   0.00000  D24
RECTANGLE         48        28   0.00000  D25
RECTANGLE         24        42   0.00000  D26
RECTANGLE         42        24   0.00000  D27
RECTANGLE         28        46   0.00000  D28
RECTANGLE         46        28   0.00000  D29
RECTANGLE         22        40   0.00000  D30
RECTANGLE         40        22   0.00000  D31
CIRCLE           186            D32
FLASH     TR182X196X40-45      0.00000  D33
CIRCLE           315            D34
CIRCLE           319            D35
CIRCLE            28            D36
CIRCLE            32            D37
CIRCLE            30            D38
FLASH     TR_C5-ALL            0.00000  D39
CIRCLE            20            D40
CIRCLE          19.3            D41
CIRCLE            34            D42
CIRCLE            26            D43
CIRCLE            24            D44
RECTANGLE         16       4.1   0.00000  D45
RECTANGLE        4.1        16   0.00000  D46
RECTANGLE         16       8.1   0.00000  D47
RECTANGLE        8.1        16   0.00000  D48
CIRCLE           291            D49
FLASH     TR136X150X40-45      0.00000  D50
CIRCLE           295            D51
CIRCLE         60.15            D52
FLASH     TR_C38-ALL           0.00000  D53
CIRCLE         65.74            D54
CIRCLE         69.74            D55
SQUARE         65.74   0.00000            D56
SQUARE         69.74   0.00000            D57
CIRCLE            42            D58
FLASH     TR_C20-ALL           0.00000  D59
CIRCLE            36            D60
CIRCLE            40            D61
RECTANGLE         24        65   0.00000  D62
RECTANGLE         65        24   0.00000  D63
RECTANGLE         28        69   0.00000  D64
RECTANGLE         69        28   0.00000  D65
RECTANGLE         20        60   0.00000  D66
RECTANGLE         60        20   0.00000  D67
RECTANGLE         35       231   0.00000  D68
RECTANGLE        231        35   0.00000  D69
CIRCLE            60            D70
FLASH     TR46X60X15-45        0.00000  D71
CIRCLE            50            D72
RECTANGLE         10        20   0.00000  D73
RECTANGLE         20        10   0.00000  D74
RECTANGLE         14        24   0.00000  D75
RECTANGLE         24        14   0.00000  D76
RECTANGLE        126       270   0.00000  D77
RECTANGLE        270       126   0.00000  D78
RECTANGLE        130       274   0.00000  D79
RECTANGLE        274       130   0.00000  D80
RECTANGLE         17        59   0.00000  D81
RECTANGLE         59        17   0.00000  D82
RECTANGLE         21        63   0.00000  D83
RECTANGLE         63        21   0.00000  D84
RECTANGLE         40        63   0.00000  D85
RECTANGLE         63        40   0.00000  D86
RECTANGLE         44        67   0.00000  D87
RECTANGLE         67        44   0.00000  D88
CIRCLE            62            D89
FLASH     TR58X72X15-45        0.00000  D90
CIRCLE            66            D91
SQUARE            62   0.00000            D92
SQUARE            66   0.00000            D93
RECTANGLE         18        52   0.00000  D94
RECTANGLE         52        18   0.00000  D95
RECTANGLE         22        56   0.00000  D96
RECTANGLE         56        22   0.00000  D97
FLASH     TR56X70X15-45        0.00000  D98
CIRCLE            64            D99
SQUARE            60   0.00000            D100
SQUARE            64   0.00000            D101
RECTANGLE         12        63   0.00000  D102
RECTANGLE         63        12   0.00000  D103
RECTANGLE         16        67   0.00000  D104
RECTANGLE         67        16   0.00000  D105
RECTANGLE         10        61   0.00000  D106
RECTANGLE         61        10   0.00000  D107
CIRCLE          25.9            D108
CIRCLE            18            D109
CIRCLE            22            D110
FLASH     TR_C6-ALL            0.00000  D111
CIRCLE            16            D112
CIRCLE          23.3            D113
RECTANGLE        130       130   0.00000  D114
RECTANGLE        134       134   0.00000  D115
CIRCLE           155            D116
FLASH     TR141X155X40-45      0.00000  D117
CIRCLE           125            D118
CIRCLE           145            D119
CIRCLE           256            D120
CIRCLE           260            D121
RECTANGLE         46        69   0.00000  D122
RECTANGLE         69        46   0.00000  D123
RECTANGLE         50        73   0.00000  D124
RECTANGLE         73        50   0.00000  D125
RECTANGLE          5        20   0.00000  D126
RECTANGLE         20         5   0.00000  D127
RECTANGLE          9        24   0.00000  D128
RECTANGLE         24         9   0.00000  D129
RECTANGLE         56        56   0.00000  D130
RECTANGLE         60        60   0.00000  D131
SQUARE           124   0.00000            D132
SQUARE           128   0.00000            D133
RECTANGLE        128       135   0.00000  D134
RECTANGLE        135       128   0.00000  D135
RECTANGLE        132       139   0.00000  D136
RECTANGLE        139       132   0.00000  D137
CIRCLE           424            D138
FLASH     TR410X424X40-45      0.00000  D139
CIRCLE           414            D140
CIRCLE           146            D141
FLASH     TR142X156X40-45      0.00000  D142
CIRCLE           197            D143
RECTANGLE         24        52   0.00000  D144
RECTANGLE         52        24   0.00000  D145
RECTANGLE         28        56   0.00000  D146
RECTANGLE         56        28   0.00000  D147
RECTANGLE        230       285   0.00000  D148
RECTANGLE        285       230   0.00000  D149
FLASH     B216-271X230-285X40   0.00000  D150
LINE             200            D151
OBLONG           200       255   0.00000  D152
OBLONG           255       200   0.00000  D153
CIRCLE           247            D154
FLASH     TR233X247X40-45      0.00000  D155
CIRCLE           217            D156
CIRCLE           237            D157
RECTANGLE         95       130   0.00000  D158
RECTANGLE        130        95   0.00000  D159
RECTANGLE         99       134   0.00000  D160
RECTANGLE        134        99   0.00000  D161
RECTANGLE        186       189   0.00000  D162
RECTANGLE        189       186   0.00000  D163
RECTANGLE        190       193   0.00000  D164
RECTANGLE        193       190   0.00000  D165
RECTANGLE         50        56   0.00000  D166
RECTANGLE         56        50   0.00000  D167
RECTANGLE         54        60   0.00000  D168
RECTANGLE         60        54   0.00000  D169
RECTANGLE         10        15   0.00000  D170
RECTANGLE         15        10   0.00000  D171
RECTANGLE         14        19   0.00000  D172
RECTANGLE         19        14   0.00000  D173
RECTANGLE         10        14   0.00000  D174
RECTANGLE         14        10   0.00000  D175
RECTANGLE         14        18   0.00000  D176
RECTANGLE         18        14   0.00000  D177
RECTANGLE         46        63   0.00000  D178
RECTANGLE         63        46   0.00000  D179
RECTANGLE         50        67   0.00000  D180
RECTANGLE         67        50   0.00000  D181
SQUARE           134   0.00000            D182
SQUARE           138   0.00000            D183
RECTANGLE          9        15   0.00000  D184
RECTANGLE         15         9   0.00000  D185
RECTANGLE         13        19   0.00000  D186
RECTANGLE         19        13   0.00000  D187
CIRCLE             9            D188
RECTANGLE         14        63   0.00000  D189
RECTANGLE         63        14   0.00000  D190
RECTANGLE         18        67   0.00000  D191
RECTANGLE         67        18   0.00000  D192
RECTANGLE         12        61   0.00000  D193
RECTANGLE         61        12   0.00000  D194
RECTANGLE         15        57   0.00000  D195
RECTANGLE         57        15   0.00000  D196
RECTANGLE         19        61   0.00000  D197
RECTANGLE         61        19   0.00000  D198
RECTANGLE         67        99   0.00000  D199
RECTANGLE         99        67   0.00000  D200
RECTANGLE         71       103   0.00000  D201
RECTANGLE        103        71   0.00000  D202
RECTANGLE         10        50   0.00000  D203
RECTANGLE         50        10   0.00000  D204
RECTANGLE         14        54   0.00000  D205
RECTANGLE         54        14   0.00000  D206
RECTANGLE         10        32   0.00000  D207
RECTANGLE         32        10   0.00000  D208
RECTANGLE         14        36   0.00000  D209
RECTANGLE         36        14   0.00000  D210
SQUARE            67   0.00000            D211
SQUARE            71   0.00000            D212
SQUARE           140   0.00000            D213
SQUARE           144   0.00000            D214
RECTANGLE         10        29   0.00000  D215
RECTANGLE         29        10   0.00000  D216
RECTANGLE         14        33   0.00000  D217
RECTANGLE         33        14   0.00000  D218
RECTANGLE         52        61   0.00000  D219
RECTANGLE         61        52   0.00000  D220
RECTANGLE         56        65   0.00000  D221
RECTANGLE         65        56   0.00000  D222
RECTANGLE         48       126   0.00000  D223
RECTANGLE        126        48   0.00000  D224
RECTANGLE         52       130   0.00000  D225
RECTANGLE        130        52   0.00000  D226
RECTANGLE         20        34   0.00000  D227
RECTANGLE         34        20   0.00000  D228
RECTANGLE         24        38   0.00000  D229
RECTANGLE         38        24   0.00000  D230
RECTANGLE         16        34   0.00000  D231
RECTANGLE         34        16   0.00000  D232
RECTANGLE         20        38   0.00000  D233
RECTANGLE         38        20   0.00000  D234
RECTANGLE         17        66   0.00000  D235
RECTANGLE         66        17   0.00000  D236
RECTANGLE         21        70   0.00000  D237
RECTANGLE         70        21   0.00000  D238
RECTANGLE         36       109   0.00000  D239
RECTANGLE        109        36   0.00000  D240
RECTANGLE         40       113   0.00000  D241
RECTANGLE        113        40   0.00000  D242
CIRCLE            70            D243
RECTANGLE         60       126   0.00000  D244
RECTANGLE        126        60   0.00000  D245
RECTANGLE         64       130   0.00000  D246
RECTANGLE        130        64   0.00000  D247
RECTANGLE         24        28   0.00000  D248
RECTANGLE         28        24   0.00000  D249
RECTANGLE         28        32   0.00000  D250
RECTANGLE         32        28   0.00000  D251
RECTANGLE         15        63   0.00000  D252
RECTANGLE         63        15   0.00000  D253
RECTANGLE         19        67   0.00000  D254
RECTANGLE         67        19   0.00000  D255
RECTANGLE         14        56   0.00000  D256
RECTANGLE         56        14   0.00000  D257
RECTANGLE         18        60   0.00000  D258
RECTANGLE         60        18   0.00000  D259
RECTANGLE         22        32   0.00000  D260
RECTANGLE         32        22   0.00000  D261
RECTANGLE         26        36   0.00000  D262
RECTANGLE         36        26   0.00000  D263
RECTANGLE         14        49   0.00000  D264
RECTANGLE         49        14   0.00000  D265
RECTANGLE         18        53   0.00000  D266
RECTANGLE         53        18   0.00000  D267
RECTANGLE         17        24   0.00000  D268
RECTANGLE         24        17   0.00000  D269
RECTANGLE         21        28   0.00000  D270
RECTANGLE         28        21   0.00000  D271
RECTANGLE         16        20   0.00000  D272
RECTANGLE         20        16   0.00000  D273
RECTANGLE         20        24   0.00000  D274
RECTANGLE         24        20   0.00000  D275
RECTANGLE          9        31   0.00000  D276
RECTANGLE         31         9   0.00000  D277
RECTANGLE         11        32   0.00000  D278
RECTANGLE         32        11   0.00000  D279
RECTANGLE         15        36   0.00000  D280
RECTANGLE         36        15   0.00000  D281
RECTANGLE         10        31   0.00000  D282
RECTANGLE         31        10   0.00000  D283
RECTANGLE         48        59   0.00000  D284
RECTANGLE         59        48   0.00000  D285
RECTANGLE         52        63   0.00000  D286
RECTANGLE         63        52   0.00000  D287
RECTANGLE         16        44   0.00000  D288
RECTANGLE         44        16   0.00000  D289
RECTANGLE         20        48   0.00000  D290
RECTANGLE         48        20   0.00000  D291
CIRCLE            17            D292
CIRCLE            87            D293
CIRCLE          78.5            D294
CIRCLE          43.5            D295
CIRCLE          31.5            D296
CIRCLE            48            D297
CIRCLE          39.5            D298
RECTANGLE         12        21   0.00000  D299
RECTANGLE         21        12   0.00000  D300
RECTANGLE         16        25   0.00000  D301
RECTANGLE         25        16   0.00000  D302
RECTANGLE         11        20   0.00000  D303
RECTANGLE         20        11   0.00000  D304
RECTANGLE         15        24   0.00000  D305
RECTANGLE         24        15   0.00000  D306
FLASH     TR83X97X25-45        0.00000  D307
CIRCLE            85            D308
CIRCLE            21            D309
CIRCLE            19            D310
LINE              15            D311
OBLONG            15        19   0.00000  D312
OBLONG            19        15   0.00000  D313
RECTANGLE         49       110   0.00000  D314
RECTANGLE        110        49   0.00000  D315
RECTANGLE         53       114   0.00000  D316
RECTANGLE        114        53   0.00000  D317
CIRCLE            95            D318
FLASH     TR81X95X15-45        0.00000  D319
CIRCLE            65            D320
CIRCLE            76            D321
FLASH     TR62X76X15-45        0.00000  D322
CIRCLE            46            D323
RECTANGLE         11        63   0.00000  D324
RECTANGLE         63        11   0.00000  D325
RECTANGLE         15        67   0.00000  D326
RECTANGLE         67        15   0.00000  D327
CIRCLE            71            D328
FLASH     TR57X71X15-45        0.00000  D329
CIRCLE            41            D330
CIRCLE            61            D331
RECTANGLE         17       185   0.00000  D332
RECTANGLE        185        17   0.00000  D333
RECTANGLE         21       189   0.00000  D334
RECTANGLE        189        21   0.00000  D335
RECTANGLE         17       100   0.00000  D336
RECTANGLE        100        17   0.00000  D337
RECTANGLE         21       104   0.00000  D338
RECTANGLE        104        21   0.00000  D339
RECTANGLE         11        90   0.00000  D340
RECTANGLE         90        11   0.00000  D341
RECTANGLE         15        94   0.00000  D342
RECTANGLE         94        15   0.00000  D343
RECTANGLE      20.47        59   0.00000  D344
RECTANGLE         59     20.47   0.00000  D345
RECTANGLE      24.47        63   0.00000  D346
RECTANGLE         63     24.47   0.00000  D347
LINE              72            D348
OBLONG           121        72   0.00000  D349
OBLONG            72       121   0.00000  D350
FLASH     TR_121_72_111_62_10_4_0   0.00000  D351
LINE              62            D352
OBLONG           111        62   0.00000  D353
OBLONG            62       111   0.00000  D354
LINE              66            D355
OBLONG           115        66   0.00000  D356
OBLONG            66       115   0.00000  D357
FLASH     TR60X74X15-45        0.00000  D358
CIRCLE            68            D359
RECTANGLE         15        50   0.00000  D360
RECTANGLE         50        15   0.00000  D361
RECTANGLE         19        54   0.00000  D362
RECTANGLE         54        19   0.00000  D363
LINE              74            D364
OBLONG            74       127   0.00000  D365
OBLONG           127        74   0.00000  D366
FLASH     B60-113X74-127X15    0.00000  D367
LINE              64            D368
OBLONG            64       137   0.00000  D369
OBLONG           137        64   0.00000  D370
LINE              68            D371
OBLONG            68       141   0.00000  D372
OBLONG           141        68   0.00000  D373
CIRCLE            74            D374
CIRCLE            44            D375
RECTANGLE         26        54   0.00000  D376
RECTANGLE         54        26   0.00000  D377
RECTANGLE         30        58   0.00000  D378
RECTANGLE         58        30   0.00000  D379
RECTANGLE         32        40   0.00000  D380
RECTANGLE         40        32   0.00000  D381
RECTANGLE         36        44   0.00000  D382
RECTANGLE         44        36   0.00000  D383
RECTANGLE          7        26   0.00000  D384
RECTANGLE         26         7   0.00000  D385
RECTANGLE         11        30   0.00000  D386
RECTANGLE         30        11   0.00000  D387
SQUARE           174   0.00000            D388
SQUARE           178   0.00000            D389
RECTANGLE          8        14   0.00000  D390
RECTANGLE         14         8   0.00000  D391
RECTANGLE         12        18   0.00000  D392
RECTANGLE         18        12   0.00000  D393
RECTANGLE         24        89   0.00000  D394
RECTANGLE         89        24   0.00000  D395
RECTANGLE         28        93   0.00000  D396
RECTANGLE         93        28   0.00000  D397
RECTANGLE         57        60   0.00000  D398
RECTANGLE         60        57   0.00000  D399
RECTANGLE         61        64   0.00000  D400
RECTANGLE         64        61   0.00000  D401
RECTANGLE         10        22   0.00000  D402
RECTANGLE         22        10   0.00000  D403
RECTANGLE         14        26   0.00000  D404
RECTANGLE         26        14   0.00000  D405
RECTANGLE         36        40   0.00000  D406
RECTANGLE         40        36   0.00000  D407
RECTANGLE         40        44   0.00000  D408
RECTANGLE         44        40   0.00000  D409
RECTANGLE         32        36   0.00000  D410
RECTANGLE         36        32   0.00000  D411
RECTANGLE         36        63   0.00000  D412
RECTANGLE         63        36   0.00000  D413
RECTANGLE         40        67   0.00000  D414
RECTANGLE         67        40   0.00000  D415
SQUARE            32   0.00000            D416
SQUARE            36   0.00000            D417
RECTANGLE         44        54   0.00000  D418
RECTANGLE         54        44   0.00000  D419
RECTANGLE         48        58   0.00000  D420
RECTANGLE         58        48   0.00000  D421
RECTANGLE         85       185   0.00000  D422
RECTANGLE        185        85   0.00000  D423
RECTANGLE         89       189   0.00000  D424
RECTANGLE        189        89   0.00000  D425
RECTANGLE       84.8       130   0.00000  D426
RECTANGLE        130      84.8   0.00000  D427
RECTANGLE       88.8       134   0.00000  D428
RECTANGLE        134      88.8   0.00000  D429
RECTANGLE        130       166   0.00000  D430
RECTANGLE        166       130   0.00000  D431
RECTANGLE        134       170   0.00000  D432
RECTANGLE        170       134   0.00000  D433
RECTANGLE        122       126   0.00000  D434
RECTANGLE        126       122   0.00000  D435
RECTANGLE        126       130   0.00000  D436
RECTANGLE        130       126   0.00000  D437
RECTANGLE         79       166   0.00000  D438
RECTANGLE        166        79   0.00000  D439
RECTANGLE         83       170   0.00000  D440
RECTANGLE        170        83   0.00000  D441
RECTANGLE         42        99   0.00000  D442
RECTANGLE         99        42   0.00000  D443
RECTANGLE         46       103   0.00000  D444
RECTANGLE        103        46   0.00000  D445
RECTANGLE        128       197   0.00000  D446
RECTANGLE        197       128   0.00000  D447
RECTANGLE        132       201   0.00000  D448
RECTANGLE        201       132   0.00000  D449
RECTANGLE         95       178   0.00000  D450
RECTANGLE        178        95   0.00000  D451
RECTANGLE         99       182   0.00000  D452
RECTANGLE        182        99   0.00000  D453
RECTANGLE         54       178   0.00000  D454
RECTANGLE        178        54   0.00000  D455
RECTANGLE         58       182   0.00000  D456
RECTANGLE        182        58   0.00000  D457
RECTANGLE         40        71   0.00000  D458
RECTANGLE         71        40   0.00000  D459
RECTANGLE         44        75   0.00000  D460
RECTANGLE         75        44   0.00000  D461
RECTANGLE         12        15   0.00000  D462
RECTANGLE         15        12   0.00000  D463
RECTANGLE         16        19   0.00000  D464
RECTANGLE         19        16   0.00000  D465
RECTANGLE         40        50   0.00000  D466
RECTANGLE         50        40   0.00000  D467
RECTANGLE         18        20   0.00000  D468
RECTANGLE         20        18   0.00000  D469
RECTANGLE         22        24   0.00000  D470
RECTANGLE         24        22   0.00000  D471
RECTANGLE         95       111   0.00000  D472
RECTANGLE        111        95   0.00000  D473
RECTANGLE         99       115   0.00000  D474
RECTANGLE        115        99   0.00000  D475
RECTANGLE         63       119   0.00000  D476
RECTANGLE        119        63   0.00000  D477
RECTANGLE         67       123   0.00000  D478
RECTANGLE        123        67   0.00000  D479
RECTANGLE         24        46   0.00000  D480
RECTANGLE         46        24   0.00000  D481
RECTANGLE         28        50   0.00000  D482
RECTANGLE         50        28   0.00000  D483
RECTANGLE         17        46   0.00000  D484
RECTANGLE         46        17   0.00000  D485
RECTANGLE         21        50   0.00000  D486
RECTANGLE         50        21   0.00000  D487
RECTANGLE         24        54   0.00000  D488
RECTANGLE         54        24   0.00000  D489
RECTANGLE         28        58   0.00000  D490
RECTANGLE         58        28   0.00000  D491
RECTANGLE         22        68   0.00000  D492
RECTANGLE         68        22   0.00000  D493
RECTANGLE         26        72   0.00000  D494
RECTANGLE         72        26   0.00000  D495
RECTANGLE         48        56   0.00000  D496
RECTANGLE         56        48   0.00000  D497
RECTANGLE         52        60   0.00000  D498
RECTANGLE         60        52   0.00000  D499
RECTANGLE         11        23   0.00000  D500
RECTANGLE         23        11   0.00000  D501
RECTANGLE         15        27   0.00000  D502
RECTANGLE         27        15   0.00000  D503
RECTANGLE         11        24   0.00000  D504
RECTANGLE         24        11   0.00000  D505
RECTANGLE         15        28   0.00000  D506
RECTANGLE         28        15   0.00000  D507
RECTANGLE         14        44   0.00000  D508
RECTANGLE         44        14   0.00000  D509
RECTANGLE         18        48   0.00000  D510
RECTANGLE         48        18   0.00000  D511
RECTANGLE         10        28   0.00000  D512
RECTANGLE         28        10   0.00000  D513
RECTANGLE         14        32   0.00000  D514
RECTANGLE         32        14   0.00000  D515
RECTANGLE         10        59   0.00000  D516
RECTANGLE         59        10   0.00000  D517
RECTANGLE         12        79   0.00000  D518
RECTANGLE         79        12   0.00000  D519
RECTANGLE         16        83   0.00000  D520
RECTANGLE         83        16   0.00000  D521
RECTANGLE         12        32   0.00000  D522
RECTANGLE         32        12   0.00000  D523
RECTANGLE         16        36   0.00000  D524
RECTANGLE         36        16   0.00000  D525
RECTANGLE          7        32   0.00000  D526
RECTANGLE         32         7   0.00000  D527
RECTANGLE         11        36   0.00000  D528
RECTANGLE         36        11   0.00000  D529
RECTANGLE         10        52   0.00000  D530
RECTANGLE         52        10   0.00000  D531
RECTANGLE         10        36   0.00000  D532
RECTANGLE         36        10   0.00000  D533
RECTANGLE         14        40   0.00000  D534
RECTANGLE         40        14   0.00000  D535
RECTANGLE         40        56   0.00000  D536
RECTANGLE         56        40   0.00000  D537
RECTANGLE         44        60   0.00000  D538
RECTANGLE         60        44   0.00000  D539
RECTANGLE         40        48   0.00000  D540
RECTANGLE         48        40   0.00000  D541
RECTANGLE         44        52   0.00000  D542
RECTANGLE         52        44   0.00000  D543
RECTANGLE         17        20   0.00000  D544
RECTANGLE         20        17   0.00000  D545
RECTANGLE         21        24   0.00000  D546
RECTANGLE         24        21   0.00000  D547
RECTANGLE         32        50   0.00000  D548
RECTANGLE         50        32   0.00000  D549
RECTANGLE         16        54   0.00000  D550
RECTANGLE         54        16   0.00000  D551
RECTANGLE         20        58   0.00000  D552
RECTANGLE         58        20   0.00000  D553
RECTANGLE         35        50   0.00000  D554
RECTANGLE         50        35   0.00000  D555
RECTANGLE         39        54   0.00000  D556
RECTANGLE         54        39   0.00000  D557
RECTANGLE         16        22   0.00000  D558
RECTANGLE         22        16   0.00000  D559
RECTANGLE         24       170   0.00000  D560
RECTANGLE        170        24   0.00000  D561
RECTANGLE         28       174   0.00000  D562
RECTANGLE        174        28   0.00000  D563
RECTANGLE         81        91   0.00000  D564
RECTANGLE         91        81   0.00000  D565
RECTANGLE         85        95   0.00000  D566
RECTANGLE         95        85   0.00000  D567
RECTANGLE         69        77   0.00000  D568
RECTANGLE         77        69   0.00000  D569
RECTANGLE         73        81   0.00000  D570
RECTANGLE         81        73   0.00000  D571
RECTANGLE         13        28   0.00000  D572
RECTANGLE         28        13   0.00000  D573
RECTANGLE          7        24   0.00000  D574
RECTANGLE         24         7   0.00000  D575
RECTANGLE         11        28   0.00000  D576
RECTANGLE         28        11   0.00000  D577
SQUARE           148   0.00000            D578
CIRCLE           142            D579
FLASH     TR138X152X40-45      0.00000  D580
CIRCLE           122            D581
CIRCLE           170            D582
FLASH     TR166X180X40-45      0.00000  D583
CIRCLE           178            D584
CIRCLE           221            D585
CIRCLE           182            D586
LINE             156            D587
OBLONG           156       219   0.00000  D588
OBLONG           219       156   0.00000  D589
FLASH     B142-205X156-219X40   0.00000  D590
LINE             126            D591
OBLONG           126       189   0.00000  D592
OBLONG           189       126   0.00000  D593
LINE             256            D594
OBLONG           256       319   0.00000  D595
OBLONG           319       256   0.00000  D596
CIRCLE            99            D597
FLASH     TR95X109X25-45       0.00000  D598
RECTANGLE        166       197   0.00000  D599
RECTANGLE        197       166   0.00000  D600
CIRCLE           158            D601
RECTANGLE        170       201   0.00000  D602
RECTANGLE        201       170   0.00000  D603
CIRCLE           162            D604
CIRCLE           165            D605
FLASH     TR151X165X40-45      0.00000  D606
CIRCLE           135            D607
CIRCLE           188            D608
FLASH     TR174X188X40-45      0.00000  D609
LINE              10            D610
OBLONG            10        13   0.00000  D611
OBLONG            13        10   0.00000  D612
CIRCLE            12            D613
CIRCLE            15            D614
RECTANGLE         52        56   0.00000  D615
RECTANGLE         56        52   0.00000  D616
RECTANGLE         56        60   0.00000  D617
RECTANGLE         60        56   0.00000  D618
SQUARE            68   0.00000            D619
CIRCLE         34.17            D620
FLASH     TR_C12-ALL           0.00000  D621
SQUARE         30.17   0.00000            D622
CIRCLE         30.17            D623
SQUARE         34.17   0.00000            D624
CIRCLE         39.68            D625
FLASH     TR_C17-ALL           0.00000  D626
CIRCLE         35.68            D627
SQUARE            61   0.00000            D628
SQUARE            65   0.00000            D629
RECTANGLE         26        38   0.00000  D630
RECTANGLE         38        26   0.00000  D631
RECTANGLE         30        42   0.00000  D632
RECTANGLE         42        30   0.00000  D633
RECTANGLE         14        58   0.00000  D634
RECTANGLE         58        14   0.00000  D635
RECTANGLE          7        22   0.00000  D636
RECTANGLE         22         7   0.00000  D637
RECTANGLE         11        26   0.00000  D638
RECTANGLE         26        11   0.00000  D639
RECTANGLE         11        18   0.00000  D640
RECTANGLE         18        11   0.00000  D641
RECTANGLE         15        22   0.00000  D642
RECTANGLE         22        15   0.00000  D643
CIRCLE            13            D644
RECTANGLE         18        28   0.00000  D645
RECTANGLE         28        18   0.00000  D646
RECTANGLE         40        15   0.00000  D647
RECTANGLE         15        40   0.00000  D648
RECTANGLE         44        19   0.00000  D649
RECTANGLE         19        44   0.00000  D650
RECTANGLE         20        28   0.00000  D651
RECTANGLE         28        20   0.00000  D652
RECTANGLE         24        24   0.00000  D653
RECTANGLE         28        28   0.00000  D654
RECTANGLE         20        20   0.00000  D655
RECTANGLE         14        59   0.00000  D656
RECTANGLE         59        14   0.00000  D657
RECTANGLE         18        63   0.00000  D658
RECTANGLE         63        18   0.00000  D659
CIRCLE            39            D660
CIRCLE           118            D661
LINE               6            D662
LINE               2            D663
LINE              40            D664
LINE               1            D665
LINE               4            D666
LINE               8            D667
LINE              25            D668
LINE             5.8            D669
LINE               5            D670
LINE              14            D671
LINE             5.1            D672
LINE             5.2            D673
LINE              20            D674
LINE             3.5            D675
LINE             7.9            D676
LINE            4.01            D677
LINE              12            D678
LINE             2.9            D679
LINE               7            D680
LINE              13            D681
LINE             4.5            D682
LINE             595            D683
LINE            3.49            D684
LINE            4.51            D685
LINE             4.2            D686
LINE              18            D687
LINE             6.8            D688
LINE            5.11            D689
LINE               9            D690
LINE              16            D691
LINE             4.4            D692
LINE             7.1            D693
LINE             4.9            D694
LINE             7.2            D695
LINE             2.6            D696
LINE             6.3            D697
LINE            6.01            D698
LINE            7.21            D699
LINE             120            D700
LINE            7.13            D701
LINE            1.75            D702
LINE             4.8            D703
LINE            2.55            D704
LINE              30            D705
LINE            38.8            D706
LINE           98.48            D707
LINE            57.7            D708
LINE           150.9            D709
LINE          329.94            D710
LINE          117.38            D711

